# T6G (Grand Teton) — schematic netlist excerpt (pin names and nets, part order shuffled) for the footprints in the layout excerpt that follows; sources: Cadence DE-HDL packaged netlist, KiCad conversion of 04192023_DAF0TMB3IC0_F0TG_MB_C_brd_V02_OCP.brd

C2571  Q_CAP  22UF 4V 20% X6S  pkg C0402  page 70 : A = PVDDCR_SOC_P0 ; B = GND
C2478  Q_CAP  22UF 4V 20% X6S  pkg C0402  page 74 : A = PVDDIO_P1 ; B = GND

(kicad_pcb
	(version 20260206)
	(generator "pcbnew")
	(generator_version "10.0")
	(general
		(thickness 1.6)
		(legacy_teardrops no)
	)
	(paper "A4")
	(title_block
		(title "04192023_DAF0TMB3IC0_F0TG_MB_C_brd_V02_OCP.brd")
		(comment 1 "Grand Teton / footprints 448-449 of 8354")
	)
	(layers
		(0 "F.Cu" signal "TOP")
		(4 "In1.Cu" signal "GND")
		(6 "In2.Cu" signal "IN1")
		(8 "In3.Cu" signal "GND1")
		(10 "In4.Cu" signal "IN2")
		(12 "In5.Cu" signal "GND2")
		(14 "In6.Cu" signal "IN3")
		(16 "In7.Cu" signal "GND3")
		(18 "In8.Cu" signal "VCC")
		(20 "In9.Cu" signal "VCC1")
		(22 "In10.Cu" signal "GND4")
		(24 "In11.Cu" signal "IN4")
		(26 "In12.Cu" signal "GND5")
		(28 "In13.Cu" signal "IN5")
		(30 "In14.Cu" signal "GND6")
		(32 "In15.Cu" signal "IN6")
		(34 "In16.Cu" signal "GND7")
		(2 "B.Cu" signal "BOTTOM")
		(9 "F.Adhes" user "F.Adhesive")
		(11 "B.Adhes" user "B.Adhesive")
		(13 "F.Paste" user "Package Geometry/Pastemask Top")
		(15 "B.Paste" user "Package Geometry/Pastemask Bottom")
		(5 "F.SilkS" user "Ref Des/Silkscreen Top")
		(7 "B.SilkS" user "Ref Des/Silkscreen Bottom")
		(1 "F.Mask" user "Board Geometry/Soldermask Top")
		(3 "B.Mask" user "Board Geometry/Soldermask Bottom")
		(17 "Dwgs.User" user "User.Drawings")
		(19 "Cmts.User" user "User.Comments")
		(21 "Eco1.User" user "User.Eco1")
		(23 "Eco2.User" user "User.Eco2")
		(25 "Edge.Cuts" user "Board Geometry/Outline")
		(27 "Margin" user)
		(31 "F.CrtYd" user "Package Geometry/Place Bound Top")
		(29 "B.CrtYd" user "Package Geometry/Place Bound Bottom")
		(35 "F.Fab" user "Ref Des/Assembly Top")
		(33 "B.Fab" user "Ref Des/Assembly Bottom")
	)
	(footprint ""
		(layer "F.Cu")
		(at 365.835692 -258.405122 180)
		(property "Reference" "C2571"
			(at 0 0 180)
			(layer "F.SilkS")
			(hide yes)
			(effects
				(font
					(size 1.27 1.27)
				)
			)
		)
		(property "Value" ""
			(at 0 0 180)
			(layer "F.Fab")
			(effects
				(font
					(size 1.27 1.27)
				)
			)
		)
		(duplicate_pad_numbers_are_jumpers no)
		(fp_line
			(start 0.7874 0.4064)
			(end -0.7874 0.4064)
			(stroke
				(width 0.1524)
				(type default)
			)
			(layer "F.SilkS")
		)
		(fp_line
			(start 0.7874 -0.4064)
			(end 0.7874 0.4064)
			(stroke
				(width 0.1524)
				(type default)
			)
			(layer "F.SilkS")
		)
		(fp_line
			(start -0.7874 0.4064)
			(end -0.7874 -0.4064)
			(stroke
				(width 0.1524)
				(type default)
			)
			(layer "F.SilkS")
		)
		(fp_line
			(start -0.7874 -0.4064)
			(end 0.7874 -0.4064)
			(stroke
				(width 0.1524)
				(type default)
			)
			(layer "F.SilkS")
		)
		(fp_line
			(start 0.67945 0.3048)
			(end 0.120396 0.3048)
			(stroke
				(width 0.1)
				(type default)
			)
			(layer "F.Fab")
		)
		(fp_line
			(start 0.67945 -0.3048)
			(end 0.67945 0.3048)
			(stroke
				(width 0.1)
				(type default)
			)
			(layer "F.Fab")
		)
		(fp_line
			(start 0.12065 -0.2794)
			(end 0.12065 -0.3048)
			(stroke
				(width 0.1)
				(type default)
			)
			(layer "F.Fab")
		)
		(fp_line
			(start 0.12065 -0.3048)
			(end 0.67945 -0.3048)
			(stroke
				(width 0.1)
				(type default)
			)
			(layer "F.Fab")
		)
		(fp_line
			(start 0.120396 0.3048)
			(end 0.120396 0.2794)
			(stroke
				(width 0.1)
				(type default)
			)
			(layer "F.Fab")
		)
		(fp_line
			(start 0.120396 0.2794)
			(end -0.12065 0.2794)
			(stroke
				(width 0.1)
				(type default)
			)
			(layer "F.Fab")
		)
		(fp_line
			(start -0.12065 0.3048)
			(end -0.67945 0.3048)
			(stroke
				(width 0.1)
				(type default)
			)
			(layer "F.Fab")
		)
		(fp_line
			(start -0.12065 0.2794)
			(end -0.12065 0.3048)
			(stroke
				(width 0.1)
				(type default)
			)
			(layer "F.Fab")
		)
		(fp_line
			(start -0.12065 -0.2794)
			(end 0.12065 -0.2794)
			(stroke
				(width 0.1)
				(type default)
			)
			(layer "F.Fab")
		)
		(fp_line
			(start -0.12065 -0.305054)
			(end -0.12065 -0.2794)
			(stroke
				(width 0.1)
				(type default)
			)
			(layer "F.Fab")
		)
		(fp_line
			(start -0.67945 0.3048)
			(end -0.67945 -0.305054)
			(stroke
				(width 0.1)
				(type default)
			)
			(layer "F.Fab")
		)
		(fp_line
			(start -0.67945 -0.305054)
			(end -0.12065 -0.305054)
			(stroke
				(width 0.1)
				(type default)
			)
			(layer "F.Fab")
		)
		(pad "1" smd circle
			(at -0.40005 0 180)
			(size 0 0)
			(layers "F.Cu" "F.Mask" "F.Paste")
			(net "PVDDCR_SOC_P0")
		)
		(pad "2" smd circle
			(at 0.40005 0 180)
			(size 0 0)
			(layers "F.Cu" "F.Mask" "F.Paste")
			(net "GND")
		)
	)
	(footprint ""
		(layer "F.Cu")
		(at 108.355892 -258.795266)
		(property "Reference" "C2478"
			(at 0 0 0)
			(layer "F.SilkS")
			(hide yes)
			(effects
				(font
					(size 1.27 1.27)
				)
			)
		)
		(property "Value" ""
			(at 0 0 0)
			(layer "F.Fab")
			(effects
				(font
					(size 1.27 1.27)
				)
			)
		)
		(duplicate_pad_numbers_are_jumpers no)
		(fp_line
			(start -0.7874 -0.4064)
			(end 0.7874 -0.4064)
			(stroke
				(width 0.1524)
				(type default)
			)
			(layer "F.SilkS")
		)
		(fp_line
			(start -0.7874 0.4064)
			(end -0.7874 -0.4064)
			(stroke
				(width 0.1524)
				(type default)
			)
			(layer "F.SilkS")
		)
		(fp_line
			(start 0.7874 -0.4064)
			(end 0.7874 0.4064)
			(stroke
				(width 0.1524)
				(type default)
			)
			(layer "F.SilkS")
		)
		(fp_line
			(start 0.7874 0.4064)
			(end -0.7874 0.4064)
			(stroke
				(width 0.1524)
				(type default)
			)
			(layer "F.SilkS")
		)
		(fp_line
			(start -0.67945 -0.305054)
			(end -0.12065 -0.305054)
			(stroke
				(width 0.1)
				(type default)
			)
			(layer "F.Fab")
		)
		(fp_line
			(start -0.67945 0.3048)
			(end -0.67945 -0.305054)
			(stroke
				(width 0.1)
				(type default)
			)
			(layer "F.Fab")
		)
		(fp_line
			(start -0.12065 -0.305054)
			(end -0.12065 -0.2794)
			(stroke
				(width 0.1)
				(type default)
			)
			(layer "F.Fab")
		)
		(fp_line
			(start -0.12065 -0.2794)
			(end 0.12065 -0.2794)
			(stroke
				(width 0.1)
				(type default)
			)
			(layer "F.Fab")
		)
		(fp_line
			(start -0.12065 0.2794)
			(end -0.12065 0.3048)
			(stroke
				(width 0.1)
				(type default)
			)
			(layer "F.Fab")
		)
		(fp_line
			(start -0.12065 0.3048)
			(end -0.67945 0.3048)
			(stroke
				(width 0.1)
				(type default)
			)
			(layer "F.Fab")
		)
		(fp_line
			(start 0.120396 0.2794)
			(end -0.12065 0.2794)
			(stroke
				(width 0.1)
				(type default)
			)
			(layer "F.Fab")
		)
		(fp_line
			(start 0.120396 0.3048)
			(end 0.120396 0.2794)
			(stroke
				(width 0.1)
				(type default)
			)
			(layer "F.Fab")
		)
		(fp_line
			(start 0.12065 -0.3048)
			(end 0.67945 -0.3048)
			(stroke
				(width 0.1)
				(type default)
			)
			(layer "F.Fab")
		)
		(fp_line
			(start 0.12065 -0.2794)
			(end 0.12065 -0.3048)
			(stroke
				(width 0.1)
				(type default)
			)
			(layer "F.Fab")
		)
		(fp_line
			(start 0.67945 -0.3048)
			(end 0.67945 0.3048)
			(stroke
				(width 0.1)
				(type default)
			)
			(layer "F.Fab")
		)
		(fp_line
			(start 0.67945 0.3048)
			(end 0.120396 0.3048)
			(stroke
				(width 0.1)
				(type default)
			)
			(layer "F.Fab")
		)
		(pad "1" smd circle
			(at -0.40005 0)
			(size 0 0)
			(layers "F.Cu" "F.Mask" "F.Paste")
			(net "PVDDIO_P1")
		)
		(pad "2" smd circle
			(at 0.40005 0)
			(size 0 0)
			(layers "F.Cu" "F.Mask" "F.Paste")
			(net "GND")
		)
	)
)
